(kicad_pcb
	(version 20260206)
	(generator "pcbnew")
	(generator_version "10.0")
	(general
		(thickness 1.6)
		(legacy_teardrops no)
	)
	(paper "A4")
	(title_block
		(title "03242023_DA0F0TMBIJ0_F0T_Motherboard_J_brd_V01_OCP.brd")
		(comment 1 "Grand Teton / footprint 1508 of 6105 (J20), pads 225-291 of 291")
	)
	(layers
		(0 "F.Cu" signal "TOP")
		(4 "In1.Cu" signal "GND")
		(6 "In2.Cu" signal "IN1")
		(8 "In3.Cu" signal "GND1")
		(10 "In4.Cu" signal "IN2")
		(12 "In5.Cu" signal "GND2")
		(14 "In6.Cu" signal "IN3")
		(16 "In7.Cu" signal "GND3")
		(18 "In8.Cu" signal "VCC")
		(20 "In9.Cu" signal "VCC1")
		(22 "In10.Cu" signal "GND4")
		(24 "In11.Cu" signal "IN4")
		(26 "In12.Cu" signal "GND5")
		(28 "In13.Cu" signal "IN5")
		(30 "In14.Cu" signal "GND6")
		(32 "In15.Cu" signal "IN6")
		(34 "In16.Cu" signal "GND7")
		(2 "B.Cu" signal "BOTTOM")
		(9 "F.Adhes" user "F.Adhesive")
		(11 "B.Adhes" user "B.Adhesive")
		(13 "F.Paste" user "Package Geometry/Pastemask Top")
		(15 "B.Paste" user "Package Geometry/Pastemask Bottom")
		(5 "F.SilkS" user "Ref Des/Silkscreen Top")
		(7 "B.SilkS" user "Ref Des/Silkscreen Bottom")
		(1 "F.Mask" user "Board Geometry/Soldermask Top")
		(3 "B.Mask" user "Board Geometry/Soldermask Bottom")
		(17 "Dwgs.User" user "User.Drawings")
		(19 "Cmts.User" user "User.Comments")
		(21 "Eco1.User" user "User.Eco1")
		(23 "Eco2.User" user "User.Eco2")
		(25 "Edge.Cuts" user "Board Geometry/Outline")
		(27 "Margin" user)
		(31 "F.CrtYd" user "Package Geometry/Place Bound Top")
		(29 "B.CrtYd" user "Package Geometry/Place Bound Bottom")
		(35 "F.Fab" user "Ref Des/Assembly Top")
		(33 "B.Fab" user "Ref Des/Assembly Bottom")
	)
	(footprint ""
		(layer "F.Cu")
		(at 47.90948 -258.091686)
		(property "Reference" "J20"
			(at -2.74066 -81.678272 0)
			(unlocked yes)
			(layer "F.SilkS")
			(effects
				(font
					(size 0.7874 0.5842)
					(thickness 0.1524)
				)
				(justify left)
			)
		)
		(property "Value" ""
			(at 0 0 0)
			(layer "F.Fab")
			(effects
				(font
					(size 1.27 1.27)
				)
			)
		)
		(duplicate_pad_numbers_are_jumpers no)
		(pad "225" smd rect
			(at 2.050034 9.774936 270)
			(size 0.519938 1.4986)
			(layers "F.Cu" "F.Mask" "F.Paste")
			(net "M_B_CPU1_SB_CA<5>")
		)
		(pad "226" smd rect
			(at 2.050034 10.625074 270)
			(size 0.519938 1.4986)
			(layers "F.Cu" "F.Mask" "F.Paste")
			(net "GND")
		)
		(pad "227" smd rect
			(at 2.050034 11.474958 270)
			(size 0.519938 1.4986)
			(layers "F.Cu" "F.Mask" "F.Paste")
			(net "M_B_CPU1_SB_PAR")
		)
		(pad "228" smd rect
			(at 2.050034 12.325096 270)
			(size 0.519938 1.4986)
			(layers "F.Cu" "F.Mask" "F.Paste")
			(net "GND")
		)
		(pad "229" smd rect
			(at 2.050034 13.17498 270)
			(size 0.519938 1.4986)
			(layers "F.Cu" "F.Mask" "F.Paste")
			(net "M_B_CPU1_SB_CS_N<3>")
		)
		(pad "230" smd rect
			(at 2.050034 14.025118 270)
			(size 0.519938 1.4986)
			(layers "F.Cu" "F.Mask" "F.Paste")
			(net "GND")
		)
		(pad "231" smd rect
			(at 2.050034 14.875002 270)
			(size 0.519938 1.4986)
			(layers "F.Cu" "F.Mask" "F.Paste")
			(net "TP_CHB_CPU1_DIMM2_FRU_5")
		)
		(pad "232" smd rect
			(at 2.050034 15.724886 270)
			(size 0.519938 1.4986)
			(layers "F.Cu" "F.Mask" "F.Paste")
			(net "TP_CHB_CPU1_DIMM2_FRU_6")
		)
		(pad "233" smd rect
			(at 2.050034 16.575024 270)
			(size 0.519938 1.4986)
			(layers "F.Cu" "F.Mask" "F.Paste")
			(net "GND")
		)
		(pad "234" smd rect
			(at 2.050034 17.424908 270)
			(size 0.519938 1.4986)
			(layers "F.Cu" "F.Mask" "F.Paste")
			(net "M_B_CPU1_SB_CB<6>")
		)
		(pad "235" smd rect
			(at 2.050034 18.275046 270)
			(size 0.519938 1.4986)
			(layers "F.Cu" "F.Mask" "F.Paste")
			(net "GND")
		)
		(pad "236" smd rect
			(at 2.050034 19.12493 270)
			(size 0.519938 1.4986)
			(layers "F.Cu" "F.Mask" "F.Paste")
			(net "M_B_CPU1_SB_CB<7>")
		)
		(pad "237" smd rect
			(at 2.050034 19.975068 270)
			(size 0.519938 1.4986)
			(layers "F.Cu" "F.Mask" "F.Paste")
			(net "GND")
		)
		(pad "238" smd rect
			(at 2.050034 20.824952 270)
			(size 0.519938 1.4986)
			(layers "F.Cu" "F.Mask" "F.Paste")
			(net "M_B_CPU1_SB_DQS_DN<4>")
		)
		(pad "239" smd rect
			(at 2.050034 21.67509 270)
			(size 0.519938 1.4986)
			(layers "F.Cu" "F.Mask" "F.Paste")
			(net "M_B_CPU1_SB_DQS_DP<4>")
		)
		(pad "240" smd rect
			(at 2.050034 22.524974 270)
			(size 0.519938 1.4986)
			(layers "F.Cu" "F.Mask" "F.Paste")
			(net "GND")
		)
		(pad "241" smd rect
			(at 2.050034 23.375112 270)
			(size 0.519938 1.4986)
			(layers "F.Cu" "F.Mask" "F.Paste")
			(net "M_B_CPU1_SB_CB<2>")
		)
		(pad "242" smd rect
			(at 2.050034 24.224996 270)
			(size 0.519938 1.4986)
			(layers "F.Cu" "F.Mask" "F.Paste")
			(net "GND")
		)
		(pad "243" smd rect
			(at 2.050034 25.07488 270)
			(size 0.519938 1.4986)
			(layers "F.Cu" "F.Mask" "F.Paste")
			(net "M_B_CPU1_SB_CB<3>")
		)
		(pad "244" smd rect
			(at 2.050034 25.925018 270)
			(size 0.519938 1.4986)
			(layers "F.Cu" "F.Mask" "F.Paste")
			(net "GND")
		)
		(pad "245" smd rect
			(at 2.050034 26.774902 270)
			(size 0.519938 1.4986)
			(layers "F.Cu" "F.Mask" "F.Paste")
			(net "M_B_CPU1_SB_DQ<2>")
		)
		(pad "246" smd rect
			(at 2.050034 27.62504 270)
			(size 0.519938 1.4986)
			(layers "F.Cu" "F.Mask" "F.Paste")
			(net "GND")
		)
		(pad "247" smd rect
			(at 2.050034 28.474924 270)
			(size 0.519938 1.4986)
			(layers "F.Cu" "F.Mask" "F.Paste")
			(net "M_B_CPU1_SB_DQ<3>")
		)
		(pad "248" smd rect
			(at 2.050034 29.325062 270)
			(size 0.519938 1.4986)
			(layers "F.Cu" "F.Mask" "F.Paste")
			(net "GND")
		)
		(pad "249" smd rect
			(at 2.050034 30.174946 270)
			(size 0.519938 1.4986)
			(layers "F.Cu" "F.Mask" "F.Paste")
			(net "M_B_CPU1_SB_DQS_DN<5>")
		)
		(pad "250" smd rect
			(at 2.050034 31.025084 270)
			(size 0.519938 1.4986)
			(layers "F.Cu" "F.Mask" "F.Paste")
			(net "M_B_CPU1_SB_DQS_DP<5>")
		)
		(pad "251" smd rect
			(at 2.050034 31.874968 270)
			(size 0.519938 1.4986)
			(layers "F.Cu" "F.Mask" "F.Paste")
			(net "GND")
		)
		(pad "252" smd rect
			(at 2.050034 32.725106 270)
			(size 0.519938 1.4986)
			(layers "F.Cu" "F.Mask" "F.Paste")
			(net "M_B_CPU1_SB_DQ<6>")
		)
		(pad "253" smd rect
			(at 2.050034 33.57499 270)
			(size 0.519938 1.4986)
			(layers "F.Cu" "F.Mask" "F.Paste")
			(net "GND")
		)
		(pad "254" smd rect
			(at 2.050034 34.425128 270)
			(size 0.519938 1.4986)
			(layers "F.Cu" "F.Mask" "F.Paste")
			(net "M_B_CPU1_SB_DQ<7>")
		)
		(pad "255" smd rect
			(at 2.050034 35.275012 270)
			(size 0.519938 1.4986)
			(layers "F.Cu" "F.Mask" "F.Paste")
			(net "GND")
		)
		(pad "256" smd rect
			(at 2.050034 36.124896 270)
			(size 0.519938 1.4986)
			(layers "F.Cu" "F.Mask" "F.Paste")
			(net "M_B_CPU1_SB_DQ<10>")
		)
		(pad "257" smd rect
			(at 2.050034 36.975034 270)
			(size 0.519938 1.4986)
			(layers "F.Cu" "F.Mask" "F.Paste")
			(net "GND")
		)
		(pad "258" smd rect
			(at 2.050034 37.824918 270)
			(size 0.519938 1.4986)
			(layers "F.Cu" "F.Mask" "F.Paste")
			(net "M_B_CPU1_SB_DQ<11>")
		)
		(pad "259" smd rect
			(at 2.050034 38.675056 270)
			(size 0.519938 1.4986)
			(layers "F.Cu" "F.Mask" "F.Paste")
			(net "GND")
		)
		(pad "260" smd rect
			(at 2.050034 39.52494 270)
			(size 0.519938 1.4986)
			(layers "F.Cu" "F.Mask" "F.Paste")
			(net "M_B_CPU1_SB_DQS_DN<6>")
		)
		(pad "261" smd rect
			(at 2.050034 40.375078 270)
			(size 0.519938 1.4986)
			(layers "F.Cu" "F.Mask" "F.Paste")
			(net "M_B_CPU1_SB_DQS_DP<6>")
		)
		(pad "262" smd rect
			(at 2.050034 41.224962 270)
			(size 0.519938 1.4986)
			(layers "F.Cu" "F.Mask" "F.Paste")
			(net "GND")
		)
		(pad "263" smd rect
			(at 2.050034 42.0751 270)
			(size 0.519938 1.4986)
			(layers "F.Cu" "F.Mask" "F.Paste")
			(net "M_B_CPU1_SB_DQ<14>")
		)
		(pad "264" smd rect
			(at 2.050034 42.924984 270)
			(size 0.519938 1.4986)
			(layers "F.Cu" "F.Mask" "F.Paste")
			(net "GND")
		)
		(pad "265" smd rect
			(at 2.050034 43.775122 270)
			(size 0.519938 1.4986)
			(layers "F.Cu" "F.Mask" "F.Paste")
			(net "M_B_CPU1_SB_DQ<15>")
		)
		(pad "266" smd rect
			(at 2.050034 44.625006 270)
			(size 0.519938 1.4986)
			(layers "F.Cu" "F.Mask" "F.Paste")
			(net "GND")
		)
		(pad "267" smd rect
			(at 2.050034 45.47489 270)
			(size 0.519938 1.4986)
			(layers "F.Cu" "F.Mask" "F.Paste")
			(net "M_B_CPU1_SB_DQ<18>")
		)
		(pad "268" smd rect
			(at 2.050034 46.325028 270)
			(size 0.519938 1.4986)
			(layers "F.Cu" "F.Mask" "F.Paste")
			(net "GND")
		)
		(pad "269" smd rect
			(at 2.050034 47.174912 270)
			(size 0.519938 1.4986)
			(layers "F.Cu" "F.Mask" "F.Paste")
			(net "M_B_CPU1_SB_DQ<19>")
		)
		(pad "270" smd rect
			(at 2.050034 48.02505 270)
			(size 0.519938 1.4986)
			(layers "F.Cu" "F.Mask" "F.Paste")
			(net "GND")
		)
		(pad "271" smd rect
			(at 2.050034 48.874934 270)
			(size 0.519938 1.4986)
			(layers "F.Cu" "F.Mask" "F.Paste")
			(net "M_B_CPU1_SB_DQS_DN<7>")
		)
		(pad "272" smd rect
			(at 2.050034 49.725072 270)
			(size 0.519938 1.4986)
			(layers "F.Cu" "F.Mask" "F.Paste")
			(net "M_B_CPU1_SB_DQS_DP<7>")
		)
		(pad "273" smd rect
			(at 2.050034 50.574956 270)
			(size 0.519938 1.4986)
			(layers "F.Cu" "F.Mask" "F.Paste")
			(net "GND")
		)
		(pad "274" smd rect
			(at 2.050034 51.425094 270)
			(size 0.519938 1.4986)
			(layers "F.Cu" "F.Mask" "F.Paste")
			(net "M_B_CPU1_SB_DQ<22>")
		)
		(pad "275" smd rect
			(at 2.050034 52.274978 270)
			(size 0.519938 1.4986)
			(layers "F.Cu" "F.Mask" "F.Paste")
			(net "GND")
		)
		(pad "276" smd rect
			(at 2.050034 53.125116 270)
			(size 0.519938 1.4986)
			(layers "F.Cu" "F.Mask" "F.Paste")
			(net "M_B_CPU1_SB_DQ<23>")
		)
		(pad "277" smd rect
			(at 2.050034 53.975 270)
			(size 0.519938 1.4986)
			(layers "F.Cu" "F.Mask" "F.Paste")
			(net "GND")
		)
		(pad "278" smd rect
			(at 2.050034 54.824884 270)
			(size 0.519938 1.4986)
			(layers "F.Cu" "F.Mask" "F.Paste")
			(net "M_B_CPU1_SB_DQ<26>")
		)
		(pad "279" smd rect
			(at 2.050034 55.675022 270)
			(size 0.519938 1.4986)
			(layers "F.Cu" "F.Mask" "F.Paste")
			(net "GND")
		)
		(pad "280" smd rect
			(at 2.050034 56.524906 270)
			(size 0.519938 1.4986)
			(layers "F.Cu" "F.Mask" "F.Paste")
			(net "M_B_CPU1_SB_DQ<27>")
		)
		(pad "281" smd rect
			(at 2.050034 57.375044 270)
			(size 0.519938 1.4986)
			(layers "F.Cu" "F.Mask" "F.Paste")
			(net "GND")
		)
		(pad "282" smd rect
			(at 2.050034 58.224928 270)
			(size 0.519938 1.4986)
			(layers "F.Cu" "F.Mask" "F.Paste")
			(net "M_B_CPU1_SB_DQS_DN<8>")
		)
		(pad "283" smd rect
			(at 2.050034 59.075066 270)
			(size 0.519938 1.4986)
			(layers "F.Cu" "F.Mask" "F.Paste")
			(net "M_B_CPU1_SB_DQS_DP<8>")
		)
		(pad "284" smd rect
			(at 2.050034 59.92495 270)
			(size 0.519938 1.4986)
			(layers "F.Cu" "F.Mask" "F.Paste")
			(net "GND")
		)
		(pad "285" smd rect
			(at 2.050034 60.775088 270)
			(size 0.519938 1.4986)
			(layers "F.Cu" "F.Mask" "F.Paste")
			(net "M_B_CPU1_SB_DQ<30>")
		)
		(pad "286" smd rect
			(at 2.050034 61.624972 270)
			(size 0.519938 1.4986)
			(layers "F.Cu" "F.Mask" "F.Paste")
			(net "GND")
		)
		(pad "287" smd rect
			(at 2.050034 62.47511 270)
			(size 0.519938 1.4986)
			(layers "F.Cu" "F.Mask" "F.Paste")
			(net "M_B_CPU1_SB_DQ<31>")
		)
		(pad "288" smd rect
			(at 2.050034 63.324994 270)
			(size 0.519938 1.4986)
			(layers "F.Cu" "F.Mask" "F.Paste")
			(net "GND")
		)
		(pad "G1" thru_hole oval
			(at 0 -68.97497)
			(size 2.8194 1.5748)
			(drill oval 2.4384 1.1938)
			(layers "*.Cu" "*.Mask")
			(remove_unused_layers no)
			(net "GND")
			(clearance 0.127)
			(thermal_gap 0.127)
		)
		(pad "G2" thru_hole oval
			(at 0 3.875024)
			(size 2.8194 1.5748)
			(drill oval 2.4384 1.1938)
			(layers "*.Cu" "*.Mask")
			(remove_unused_layers no)
			(net "GND")
			(clearance 0.127)
			(thermal_gap 0.127)
		)
		(pad "G3" thru_hole oval
			(at 0 68.97497)
			(size 2.8194 1.5748)
			(drill oval 2.4384 1.1938)
			(layers "*.Cu" "*.Mask")
			(remove_unused_layers no)
			(net "GND")
			(clearance 0.127)
			(thermal_gap 0.127)
		)
	)
)
